(kicad_pcb
	(version 20240108)
	(generator "pcbnew")
	(generator_version "8.0")
	(general
		(thickness 1.62)
		(legacy_teardrops no)
	)
	(paper "A4")
	(title_block
		(title "Jetson Orin Baseboard")
		(date "2025-03-12")
		(rev "1.3.4")
		(company "Antmicro Ltd")
		(comment 1 "www.antmicro.com")
		(comment 9 "footprint 59 of 677 (J15), pads 86-170 of 264")
	)
	(layers
		(0 "F.Cu" signal)
		(1 "In1.Cu" signal)
		(2 "In2.Cu" signal)
		(3 "In3.Cu" signal)
		(4 "In4.Cu" jumper)
		(5 "In5.Cu" signal)
		(6 "In6.Cu" signal)
		(31 "B.Cu" signal)
		(32 "B.Adhes" user "B.Adhesive")
		(33 "F.Adhes" user "F.Adhesive")
		(34 "B.Paste" user)
		(35 "F.Paste" user)
		(36 "B.SilkS" user "B.Silkscreen")
		(37 "F.SilkS" user "F.Silkscreen")
		(38 "B.Mask" user)
		(39 "F.Mask" user)
		(40 "Dwgs.User" user "User.Drawings")
		(41 "Cmts.User" user "User.Comments")
		(42 "Eco1.User" user "User.Eco1")
		(43 "Eco2.User" user "User.Eco2")
		(44 "Edge.Cuts" user)
		(45 "Margin" user)
		(46 "B.CrtYd" user "B.Courtyard")
		(47 "F.CrtYd" user "F.Courtyard")
		(48 "B.Fab" user)
		(49 "F.Fab" user)
	)
	(footprint "antmicro-footprints:TE_2309413"
		(locked yes)
		(layer "F.Cu")
		(at 92.706 84.0225)
		(descr "260 pin DDR4 SODIMM Right Angle Socket, 9.2 mm (0.362 in) Stack Height, https://www.te.com/global-en/product-2309413-1.html")
		(tags "ddr4 sodimm right angle 9.2mm height jetson som")
		(property "Reference" "J15"
			(at -36.75 -13.25 0)
			(layer "F.SilkS")
			(effects
				(font
					(size 0.7 0.7)
					(thickness 0.15)
				)
				(justify left bottom)
			)
		)
		(property "Value" "Bus_DDR4_SODIMM_CUSTOM_Jetson-Orin-H9.2mm-socket"
			(at -38 14.25 0)
			(layer "F.Fab")
			(effects
				(font
					(size 0.7 0.7)
					(thickness 0.15)
				)
				(justify left bottom)
			)
		)
		(property "Footprint" "antmicro-footprints:TE_2309413"
			(at 0 0 0)
			(layer "F.Fab")
			(hide yes)
			(effects
				(font
					(size 1.27 1.27)
					(thickness 0.15)
				)
			)
		)
		(property "Datasheet" "https://developer.nvidia.com/jetson-orin-nx-series-data-sheet"
			(at 0 0 0)
			(layer "F.Fab")
			(hide yes)
			(effects
				(font
					(size 1.27 1.27)
					(thickness 0.15)
				)
			)
		)
		(property "Author" "Antmicro"
			(at 0 0 0)
			(layer "F.Fab")
			(hide yes)
			(effects
				(font
					(size 1 1)
					(thickness 0.15)
				)
			)
		)
		(property "License" "Apache-2.0"
			(at 0 0 0)
			(layer "F.Fab")
			(hide yes)
			(effects
				(font
					(size 1 1)
					(thickness 0.15)
				)
			)
		)
		(property "MPN" "2309413-1"
			(at 0 0 0)
			(layer "F.Fab")
			(hide yes)
			(effects
				(font
					(size 1 1)
					(thickness 0.15)
				)
			)
		)
		(property "Manufacturer" "TE Connectivity"
			(at 0 0 0)
			(layer "F.Fab")
			(hide yes)
			(effects
				(font
					(size 1 1)
					(thickness 0.15)
				)
			)
		)
		(sheetname "SoM")
		(sheetfile "som.kicad_sch")
		(attr smd)
		(pad "84" smd rect
			(at 12.62 -3.826 90)
			(size 1.75 0.3)
			(layers "F.Cu" "F.Paste" "F.Mask")
			(net 738 "unconnected-(J15B-DSI_D1_P-Pad84)")
			(pinfunction "DSI_D1_P")
			(pintype "passive+no_connect")
		)
		(pad "85" smd rect
			(at 12.37 -12.026 90)
			(size 1.75 0.3)
			(layers "F.Cu" "F.Paste" "F.Mask")
			(net 1 "GND")
			(pinfunction "GND")
			(pintype "passive")
		)
		(pad "86" smd rect
			(at 12.12 -3.826 90)
			(size 1.75 0.3)
			(layers "F.Cu" "F.Paste" "F.Mask")
			(net 1 "GND")
			(pinfunction "GND")
			(pintype "passive")
		)
		(pad "87" smd rect
			(at 11.87 -12.026 90)
			(size 1.75 0.3)
			(layers "F.Cu" "F.Paste" "F.Mask")
			(net 116 "USB_FLASH_ID")
			(pinfunction "USB_VBUS_EN0/GPIO00")
			(pintype "passive")
		)
		(pad "88" smd rect
			(at 11.62 -3.826 90)
			(size 1.75 0.3)
			(layers "F.Cu" "F.Paste" "F.Mask")
			(net 739 "unconnected-(J15E-DP0_HPD-Pad88)")
			(pinfunction "DP0_HPD")
			(pintype "passive+no_connect")
		)
		(pad "89" smd rect
			(at 11.37 -12.026 90)
			(size 1.75 0.3)
			(layers "F.Cu" "F.Paste" "F.Mask")
			(net 30 "SPIO_MOSI")
			(pinfunction "SPI0_MOSI")
			(pintype "passive")
		)
		(pad "90" smd rect
			(at 11.12 -3.826 90)
			(size 1.75 0.3)
			(layers "F.Cu" "F.Paste" "F.Mask")
			(net 740 "unconnected-(J15E-DP0_AUX_N-Pad90)")
			(pinfunction "DP0_AUX_N")
			(pintype "passive+no_connect")
		)
		(pad "91" smd rect
			(at 10.87 -12.026 90)
			(size 1.75 0.3)
			(layers "F.Cu" "F.Paste" "F.Mask")
			(net 31 "SPIO_SCK")
			(pinfunction "SPI0_SCK")
			(pintype "passive")
		)
		(pad "92" smd rect
			(at 10.62 -3.826 90)
			(size 1.75 0.3)
			(layers "F.Cu" "F.Paste" "F.Mask")
			(net 741 "unconnected-(J15E-DP0_AUX_P-Pad92)")
			(pinfunction "DP0_AUX_P")
			(pintype "passive+no_connect")
		)
		(pad "93" smd rect
			(at 10.37 -12.026 90)
			(size 1.75 0.3)
			(layers "F.Cu" "F.Paste" "F.Mask")
			(net 32 "SPIO_MISO")
			(pinfunction "SPI0_MISO")
			(pintype "passive")
		)
		(pad "94" smd rect
			(at 10.12 -3.826 90)
			(size 1.75 0.3)
			(layers "F.Cu" "F.Paste" "F.Mask")
			(net 742 "Net-(J15E-HDMI_CEC)")
			(pinfunction "HDMI_CEC")
			(pintype "passive")
		)
		(pad "95" smd rect
			(at 9.87 -12.026 90)
			(size 1.75 0.3)
			(layers "F.Cu" "F.Paste" "F.Mask")
			(net 33 "~{SPI0_CS0}")
			(pinfunction "~{SPI0_CS0}")
			(pintype "passive")
		)
		(pad "96" smd rect
			(at 9.62 -3.826 90)
			(size 1.75 0.3)
			(layers "F.Cu" "F.Paste" "F.Mask")
			(net 428 "DP1_HPD")
			(pinfunction "DP1_HPD")
			(pintype "passive")
		)
		(pad "97" smd rect
			(at 9.37 -12.026 90)
			(size 1.75 0.3)
			(layers "F.Cu" "F.Paste" "F.Mask")
			(net 34 "~{SPI0_CS1}")
			(pinfunction "~{SPI0_CS1}")
			(pintype "passive")
		)
		(pad "98" smd rect
			(at 9.12 -3.826 90)
			(size 1.75 0.3)
			(layers "F.Cu" "F.Paste" "F.Mask")
			(net 430 "DP1_HDMI_AUX_N")
			(pinfunction "DP1_AUX_N")
			(pintype "passive")
		)
		(pad "99" smd rect
			(at 8.87 -12.026 90)
			(size 1.75 0.3)
			(layers "F.Cu" "F.Paste" "F.Mask")
			(net 517 "UART0_TXD")
			(pinfunction "UART0_TXD")
			(pintype "passive")
		)
		(pad "100" smd rect
			(at 8.62 -3.826 90)
			(size 1.75 0.3)
			(layers "F.Cu" "F.Paste" "F.Mask")
			(net 429 "DP1_HDMI_AUX_P")
			(pinfunction "DP1_AUX_P")
			(pintype "passive")
		)
		(pad "101" smd rect
			(at 8.37 -12.026 90)
			(size 1.75 0.3)
			(layers "F.Cu" "F.Paste" "F.Mask")
			(net 516 "UART0_RXD")
			(pinfunction "UART0_RXD")
			(pintype "passive")
		)
		(pad "102" smd rect
			(at 8.12 -3.826 90)
			(size 1.75 0.3)
			(layers "F.Cu" "F.Paste" "F.Mask")
			(net 1 "GND")
			(pinfunction "GND")
			(pintype "passive")
		)
		(pad "103" smd rect
			(at 7.869 -12.026 90)
			(size 1.75 0.3)
			(layers "F.Cu" "F.Paste" "F.Mask")
			(net 118 "UART0_RTS")
			(pinfunction "~{UART0_RTS}")
			(pintype "passive")
		)
		(pad "104" smd rect
			(at 7.619 -3.826 90)
			(size 1.75 0.3)
			(layers "F.Cu" "F.Paste" "F.Mask")
			(net 37 "SPI1_MOSI")
			(pinfunction "SPI1_MOSI")
			(pintype "passive")
		)
		(pad "105" smd rect
			(at 7.369 -12.026 90)
			(size 1.75 0.3)
			(layers "F.Cu" "F.Paste" "F.Mask")
			(net 119 "UART0_CTS")
			(pinfunction "~{UART0_CTS}")
			(pintype "passive")
		)
		(pad "106" smd rect
			(at 7.119 -3.826 90)
			(size 1.75 0.3)
			(layers "F.Cu" "F.Paste" "F.Mask")
			(net 38 "SPI1_SCK")
			(pinfunction "SPI1_SCK")
			(pintype "passive")
		)
		(pad "107" smd rect
			(at 6.869 -12.026 90)
			(size 1.75 0.3)
			(layers "F.Cu" "F.Paste" "F.Mask")
			(net 1 "GND")
			(pinfunction "GND")
			(pintype "passive")
		)
		(pad "108" smd rect
			(at 6.619 -3.826 90)
			(size 1.75 0.3)
			(layers "F.Cu" "F.Paste" "F.Mask")
			(net 39 "SPI1_MISO")
			(pinfunction "SPI1_MISO")
			(pintype "passive")
		)
		(pad "109" smd rect
			(at 6.369 -12.026 90)
			(size 1.75 0.3)
			(layers "F.Cu" "F.Paste" "F.Mask")
			(net 40 "USB0_D_N")
			(pinfunction "USB0_D_N")
			(pintype "passive")
		)
		(pad "110" smd rect
			(at 6.119 -3.826 90)
			(size 1.75 0.3)
			(layers "F.Cu" "F.Paste" "F.Mask")
			(net 41 "~{SPI1_CS0}")
			(pinfunction "~{SPI1_CS0}")
			(pintype "passive")
		)
		(pad "111" smd rect
			(at 5.869 -12.026 90)
			(size 1.75 0.3)
			(layers "F.Cu" "F.Paste" "F.Mask")
			(net 433 "USB0_D_P")
			(pinfunction "USB0_D_P")
			(pintype "passive")
		)
		(pad "112" smd rect
			(at 5.619 -3.826 90)
			(size 1.75 0.3)
			(layers "F.Cu" "F.Paste" "F.Mask")
			(net 42 "~{SPI1_CS1}")
			(pinfunction "~{SPI1_CS1}")
			(pintype "passive")
		)
		(pad "113" smd rect
			(at 5.369 -12.026 90)
			(size 1.75 0.3)
			(layers "F.Cu" "F.Paste" "F.Mask")
			(net 1 "GND")
			(pinfunction "GND")
			(pintype "passive")
		)
		(pad "114" smd rect
			(at 5.12 -3.826 90)
			(size 1.75 0.3)
			(layers "F.Cu" "F.Paste" "F.Mask")
			(net 743 "Net-(J15B-CAM0_PWDN)")
			(pinfunction "CAM0_PWDN")
			(pintype "passive")
		)
		(pad "115" smd rect
			(at 4.87 -12.026 90)
			(size 1.75 0.3)
			(layers "F.Cu" "F.Paste" "F.Mask")
			(net 434 "USB1_D_N")
			(pinfunction "USB1_D_N")
			(pintype "passive")
		)
		(pad "116" smd rect
			(at 4.62 -3.826 90)
			(size 1.75 0.3)
			(layers "F.Cu" "F.Paste" "F.Mask")
			(net 744 "Net-(J15B-CAM0_MCLK)")
			(pinfunction "CAM0_MCLK")
			(pintype "passive")
		)
		(pad "117" smd rect
			(at 4.37 -12.026 90)
			(size 1.75 0.3)
			(layers "F.Cu" "F.Paste" "F.Mask")
			(net 436 "USB1_D_P")
			(pinfunction "USB1_D_P")
			(pintype "passive")
		)
		(pad "118" smd rect
			(at 4.12 -3.826 90)
			(size 1.75 0.3)
			(layers "F.Cu" "F.Paste" "F.Mask")
			(net 43 "GPIO01")
			(pinfunction "GPIO01/CLK")
			(pintype "passive")
		)
		(pad "119" smd rect
			(at 3.87 -12.026 90)
			(size 1.75 0.3)
			(layers "F.Cu" "F.Paste" "F.Mask")
			(net 1 "GND")
			(pinfunction "GND")
			(pintype "passive")
		)
		(pad "120" smd rect
			(at 3.62 -3.826 90)
			(size 1.75 0.3)
			(layers "F.Cu" "F.Paste" "F.Mask")
			(net 745 "Net-(J15B-CAM1_PWDN)")
			(pinfunction "CAM1_PWDN")
			(pintype "passive")
		)
		(pad "121" smd rect
			(at 3.37 -12.026 90)
			(size 1.75 0.3)
			(layers "F.Cu" "F.Paste" "F.Mask")
			(net 437 "USB2_D_N")
			(pinfunction "USB2_D_N")
			(pintype "passive")
		)
		(pad "122" smd rect
			(at 3.12 -3.826 90)
			(size 1.75 0.3)
			(layers "F.Cu" "F.Paste" "F.Mask")
			(net 746 "Net-(J15B-CAM1_MCLK)")
			(pinfunction "CAM1_MCLK")
			(pintype "passive")
		)
		(pad "123" smd rect
			(at 2.87 -12.026 90)
			(size 1.75 0.3)
			(layers "F.Cu" "F.Paste" "F.Mask")
			(net 439 "USB2_D_P")
			(pinfunction "USB2_D_P")
			(pintype "passive")
		)
		(pad "124" smd rect
			(at 2.62 -3.826 90)
			(size 1.75 0.3)
			(layers "F.Cu" "F.Paste" "F.Mask")
			(net 747 "Net-(J15H-GPIO02)")
			(pinfunction "GPIO02")
			(pintype "passive")
		)
		(pad "125" smd rect
			(at 2.37 -12.026 90)
			(size 1.75 0.3)
			(layers "F.Cu" "F.Paste" "F.Mask")
			(net 1 "GND")
			(pinfunction "GND")
			(pintype "passive")
		)
		(pad "126" smd rect
			(at 2.12 -3.826 90)
			(size 1.75 0.3)
			(layers "F.Cu" "F.Paste" "F.Mask")
			(net 440 "USER_LED0")
			(pinfunction "GPIO03")
			(pintype "passive")
		)
		(pad "127" smd rect
			(at 1.87 -12.026 90)
			(size 1.75 0.3)
			(layers "F.Cu" "F.Paste" "F.Mask")
			(net 44 "USER_LED1")
			(pinfunction "GPIO04")
			(pintype "passive")
		)
		(pad "128" smd rect
			(at 1.62 -3.826 90)
			(size 1.75 0.3)
			(layers "F.Cu" "F.Paste" "F.Mask")
			(net 45 "USER_BTN0")
			(pinfunction "GPIO05")
			(pintype "passive")
		)
		(pad "129" smd rect
			(at 1.37 -12.026 90)
			(size 1.75 0.3)
			(layers "F.Cu" "F.Paste" "F.Mask")
			(net 1 "GND")
			(pinfunction "GND")
			(pintype "passive")
		)
		(pad "130" smd rect
			(at 1.12 -3.826 90)
			(size 1.75 0.3)
			(layers "F.Cu" "F.Paste" "F.Mask")
			(net 46 "USER_BTN1")
			(pinfunction "GPIO06")
			(pintype "passive")
		)
		(pad "131" smd rect
			(at 0.869 -12.026 90)
			(size 1.75 0.3)
			(layers "F.Cu" "F.Paste" "F.Mask")
			(net 47 "PCIE0_RX0_N")
			(pinfunction "PCIE0_RX0_N")
			(pintype "passive")
		)
		(pad "132" smd rect
			(at 0.619 -3.826 90)
			(size 1.75 0.3)
			(layers "F.Cu" "F.Paste" "F.Mask")
			(net 1 "GND")
			(pinfunction "GND")
			(pintype "passive")
		)
		(pad "133" smd rect
			(at 0.369 -12.026 90)
			(size 1.75 0.3)
			(layers "F.Cu" "F.Paste" "F.Mask")
			(net 48 "PCIE0_RX0_P")
			(pinfunction "PCIE0_RX0_P")
			(pintype "passive")
		)
		(pad "134" smd rect
			(at 0.119 -3.826 90)
			(size 1.75 0.3)
			(layers "F.Cu" "F.Paste" "F.Mask")
			(net 441 "PCIE0_TX0_N")
			(pinfunction "PCIE0_TX0_N")
			(pintype "passive")
		)
		(pad "135" smd rect
			(at -0.131 -12.026 90)
			(size 1.75 0.3)
			(layers "F.Cu" "F.Paste" "F.Mask")
			(net 1 "GND")
			(pinfunction "GND")
			(pintype "passive")
		)
		(pad "136" smd rect
			(at -0.38 -3.826 90)
			(size 1.75 0.3)
			(layers "F.Cu" "F.Paste" "F.Mask")
			(net 442 "PCIE0_TX0_P")
			(pinfunction "PCIE0_TX0_P")
			(pintype "passive")
		)
		(pad "137" smd rect
			(at -0.63 -12.026 90)
			(size 1.75 0.3)
			(layers "F.Cu" "F.Paste" "F.Mask")
			(net 49 "PCIE0_RX1_N")
			(pinfunction "PCIE0_RX1_N")
			(pintype "passive")
		)
		(pad "138" smd rect
			(at -0.88 -3.826 90)
			(size 1.75 0.3)
			(layers "F.Cu" "F.Paste" "F.Mask")
			(net 1 "GND")
			(pinfunction "GND")
			(pintype "passive")
		)
		(pad "139" smd rect
			(at -1.131 -12.026 90)
			(size 1.75 0.3)
			(layers "F.Cu" "F.Paste" "F.Mask")
			(net 50 "PCIE0_RX1_P")
			(pinfunction "PCIE0_RX1_P")
			(pintype "passive")
		)
		(pad "140" smd rect
			(at -1.381 -3.826 90)
			(size 1.75 0.3)
			(layers "F.Cu" "F.Paste" "F.Mask")
			(net 443 "PCIE0_TX1_N")
			(pinfunction "PCIE0_TX1_N")
			(pintype "passive")
		)
		(pad "141" smd rect
			(at -1.631 -12.026 90)
			(size 1.75 0.3)
			(layers "F.Cu" "F.Paste" "F.Mask")
			(net 1 "GND")
			(pinfunction "GND")
			(pintype "passive")
		)
		(pad "142" smd rect
			(at -1.881 -3.826 90)
			(size 1.75 0.3)
			(layers "F.Cu" "F.Paste" "F.Mask")
			(net 444 "PCIE0_TX1_P")
			(pinfunction "PCIE0_TX1_P")
			(pintype "passive")
		)
		(pad "143" smd rect
			(at -2.13 -12.026 90)
			(size 1.75 0.3)
			(layers "F.Cu" "F.Paste" "F.Mask")
			(net 100 "CAN_RX")
			(pinfunction "CAN_RX")
			(pintype "passive")
		)
		(pad "144" smd rect
			(at -2.38 -3.826 90)
			(size 1.75 0.3)
			(layers "F.Cu" "F.Paste" "F.Mask")
			(net 1 "GND")
			(pinfunction "GND")
			(pintype "passive")
		)
		(pad "145" smd rect
			(at -4.63 -12.026 90)
			(size 1.75 0.3)
			(layers "F.Cu" "F.Paste" "F.Mask")
			(net 101 "CAN_TX")
			(pinfunction "CAN_TX")
			(pintype "passive")
		)
		(pad "146" smd rect
			(at -4.88 -3.826 90)
			(size 1.75 0.3)
			(layers "F.Cu" "F.Paste" "F.Mask")
			(net 1 "GND")
			(pinfunction "GND")
			(pintype "passive")
		)
		(pad "147" smd rect
			(at -5.13 -12.026 90)
			(size 1.75 0.3)
			(layers "F.Cu" "F.Paste" "F.Mask")
			(net 1 "GND")
			(pinfunction "GND")
			(pintype "passive")
		)
		(pad "148" smd rect
			(at -5.38 -3.826 90)
			(size 1.75 0.3)
			(layers "F.Cu" "F.Paste" "F.Mask")
			(net 445 "PCIE0_TX2_N")
			(pinfunction "PCIE0_TX2_N")
			(pintype "passive")
		)
		(pad "149" smd rect
			(at -5.63 -12.026 90)
			(size 1.75 0.3)
			(layers "F.Cu" "F.Paste" "F.Mask")
			(net 51 "PCIE0_RX2_N")
			(pinfunction "PCIE0_RX2_N")
			(pintype "passive")
		)
		(pad "150" smd rect
			(at -5.88 -3.826 90)
			(size 1.75 0.3)
			(layers "F.Cu" "F.Paste" "F.Mask")
			(net 446 "PCIE0_TX2_P")
			(pinfunction "PCIE0_TX2_P")
			(pintype "passive")
		)
		(pad "151" smd rect
			(at -6.13 -12.026 90)
			(size 1.75 0.3)
			(layers "F.Cu" "F.Paste" "F.Mask")
			(net 52 "PCIE0_RX2_P")
			(pinfunction "PCIE0_RX2_P")
			(pintype "passive")
		)
		(pad "152" smd rect
			(at -6.38 -3.826 90)
			(size 1.75 0.3)
			(layers "F.Cu" "F.Paste" "F.Mask")
			(net 1 "GND")
			(pinfunction "GND")
			(pintype "passive")
		)
		(pad "153" smd rect
			(at -6.63 -12.026 90)
			(size 1.75 0.3)
			(layers "F.Cu" "F.Paste" "F.Mask")
			(net 1 "GND")
			(pinfunction "GND")
			(pintype "passive")
		)
		(pad "154" smd rect
			(at -6.88 -3.826 90)
			(size 1.75 0.3)
			(layers "F.Cu" "F.Paste" "F.Mask")
			(net 447 "PCIE0_TX3_N")
			(pinfunction "PCIE0_TX3_N")
			(pintype "passive")
		)
		(pad "155" smd rect
			(at -7.13 -12.026 90)
			(size 1.75 0.3)
			(layers "F.Cu" "F.Paste" "F.Mask")
			(net 53 "PCIE0_RX3_N")
			(pinfunction "PCIE0_RX3_N")
			(pintype "passive")
		)
		(pad "156" smd rect
			(at -7.38 -3.826 90)
			(size 1.75 0.3)
			(layers "F.Cu" "F.Paste" "F.Mask")
			(net 448 "PCIE0_TX3_P")
			(pinfunction "PCIE0_TX3_P")
			(pintype "passive")
		)
		(pad "157" smd rect
			(at -7.63 -12.026 90)
			(size 1.75 0.3)
			(layers "F.Cu" "F.Paste" "F.Mask")
			(net 54 "PCIE0_RX3_P")
			(pinfunction "PCIE0_RX3_P")
			(pintype "passive")
		)
		(pad "158" smd rect
			(at -7.88 -3.826 90)
			(size 1.75 0.3)
			(layers "F.Cu" "F.Paste" "F.Mask")
			(net 1 "GND")
			(pinfunction "GND")
			(pintype "passive")
		)
		(pad "159" smd rect
			(at -8.131 -12.026 90)
			(size 1.75 0.3)
			(layers "F.Cu" "F.Paste" "F.Mask")
			(net 1 "GND")
			(pinfunction "GND")
			(pintype "passive")
		)
		(pad "160" smd rect
			(at -8.381 -3.826 90)
			(size 1.75 0.3)
			(layers "F.Cu" "F.Paste" "F.Mask")
			(net 55 "PCIE0_CLK_N")
			(pinfunction "PCIE0_CLK_N")
			(pintype "passive")
		)
		(pad "161" smd rect
			(at -8.631 -12.026 90)
			(size 1.75 0.3)
			(layers "F.Cu" "F.Paste" "F.Mask")
			(net 56 "USBSS0_RX_N")
			(pinfunction "USBSS0_RX_N")
			(pintype "passive")
		)
		(pad "162" smd rect
			(at -8.881 -3.826 90)
			(size 1.75 0.3)
			(layers "F.Cu" "F.Paste" "F.Mask")
			(net 57 "PCIE0_CLK_P")
			(pinfunction "PCIE0_CLK_P")
			(pintype "passive")
		)
		(pad "163" smd rect
			(at -9.131 -12.026 90)
			(size 1.75 0.3)
			(layers "F.Cu" "F.Paste" "F.Mask")
			(net 58 "USBSS0_RX_P")
			(pinfunction "USBSS0_RX_P")
			(pintype "passive")
		)
		(pad "164" smd rect
			(at -9.381 -3.826 90)
			(size 1.75 0.3)
			(layers "F.Cu" "F.Paste" "F.Mask")
			(net 1 "GND")
			(pinfunction "GND")
			(pintype "passive")
		)
		(pad "165" smd rect
			(at -9.631 -12.026 90)
			(size 1.75 0.3)
			(layers "F.Cu" "F.Paste" "F.Mask")
			(net 1 "GND")
			(pinfunction "GND")
			(pintype "passive")
		)
		(pad "166" smd rect
			(at -9.881 -3.826 90)
			(size 1.75 0.3)
			(layers "F.Cu" "F.Paste" "F.Mask")
			(net 59 "USBSS0_TX_N")
			(pinfunction "USBSS0_TX_N")
			(pintype "passive")
		)
		(pad "167" smd rect
			(at -10.131 -12.026 90)
			(size 1.75 0.3)
			(layers "F.Cu" "F.Paste" "F.Mask")
			(net 60 "PCIE1_RX0_N")
			(pinfunction "PCIE1_RX0_N")
			(pintype "passive")
		)
		(pad "168" smd rect
			(at -10.381 -3.826 90)
			(size 1.75 0.3)
			(layers "F.Cu" "F.Paste" "F.Mask")
			(net 449 "USBSS0_TX_P")
			(pinfunction "USBSS0_TX_P")
			(pintype "passive")
		)
	)
)
